(kicad_pcb
	(version 20260206)
	(generator "pcbnew")
	(generator_version "10.0")
	(general
		(thickness 1.6)
		(legacy_teardrops no)
	)
	(paper "A4")
	(title_block
		(title "03242023_DA0F0TMBIJ0_F0T_Motherboard_J_brd_V01_OCP.brd")
		(comment 1 "Grand Teton / footprint 3900 of 6105 (J31), pads 1-112 of 291")
	)
	(layers
		(0 "F.Cu" signal "TOP")
		(4 "In1.Cu" signal "GND")
		(6 "In2.Cu" signal "IN1")
		(8 "In3.Cu" signal "GND1")
		(10 "In4.Cu" signal "IN2")
		(12 "In5.Cu" signal "GND2")
		(14 "In6.Cu" signal "IN3")
		(16 "In7.Cu" signal "GND3")
		(18 "In8.Cu" signal "VCC")
		(20 "In9.Cu" signal "VCC1")
		(22 "In10.Cu" signal "GND4")
		(24 "In11.Cu" signal "IN4")
		(26 "In12.Cu" signal "GND5")
		(28 "In13.Cu" signal "IN5")
		(30 "In14.Cu" signal "GND6")
		(32 "In15.Cu" signal "IN6")
		(34 "In16.Cu" signal "GND7")
		(2 "B.Cu" signal "BOTTOM")
		(9 "F.Adhes" user "F.Adhesive")
		(11 "B.Adhes" user "B.Adhesive")
		(13 "F.Paste" user "Package Geometry/Pastemask Top")
		(15 "B.Paste" user "Package Geometry/Pastemask Bottom")
		(5 "F.SilkS" user "Ref Des/Silkscreen Top")
		(7 "B.SilkS" user "Ref Des/Silkscreen Bottom")
		(1 "F.Mask" user "Board Geometry/Soldermask Top")
		(3 "B.Mask" user "Board Geometry/Soldermask Bottom")
		(17 "Dwgs.User" user "User.Drawings")
		(19 "Cmts.User" user "User.Comments")
		(21 "Eco1.User" user "User.Eco1")
		(23 "Eco2.User" user "User.Eco2")
		(25 "Edge.Cuts" user "Board Geometry/Outline")
		(27 "Margin" user)
		(31 "F.CrtYd" user "Package Geometry/Place Bound Top")
		(29 "B.CrtYd" user "Package Geometry/Place Bound Bottom")
		(35 "F.Fab" user "Ref Des/Assembly Top")
		(33 "B.Fab" user "Ref Des/Assembly Bottom")
	)
	(footprint ""
		(layer "F.Cu")
		(at 213.66988 -258.091686)
		(property "Reference" "J31"
			(at -3.683 -81.702148 0)
			(unlocked yes)
			(layer "F.SilkS")
			(effects
				(font
					(size 0.7874 0.5842)
					(thickness 0.1524)
				)
				(justify left)
			)
		)
		(property "Value" ""
			(at 0 0 0)
			(layer "F.Fab")
			(effects
				(font
					(size 1.27 1.27)
				)
			)
		)
		(duplicate_pad_numbers_are_jumpers no)
		(pad "1" smd rect
			(at -2.050034 -63.324994 270)
			(size 0.519938 1.4986)
			(layers "F.Cu" "F.Mask" "F.Paste")
			(net "P12V_S3_AUX_CPU1_NVDIMM")
		)
		(pad "2" smd rect
			(at -2.050034 -62.47511 270)
			(size 0.519938 1.4986)
			(layers "F.Cu" "F.Mask" "F.Paste")
			(net "TP_CHH_CPU1_DIMM1_FRU_0")
		)
		(pad "3" smd rect
			(at -2.050034 -61.624972 270)
			(size 0.519938 1.4986)
			(layers "F.Cu" "F.Mask" "F.Paste")
			(net "P3V3_AUX")
		)
		(pad "4" smd rect
			(at -2.050034 -60.775088 270)
			(size 0.519938 1.4986)
			(layers "F.Cu" "F.Mask" "F.Paste")
			(net "I3C_SPD_DDREFGH_CPU1_LVC1_SCL_6")
		)
		(pad "5" smd rect
			(at -2.050034 -59.92495 270)
			(size 0.519938 1.4986)
			(layers "F.Cu" "F.Mask" "F.Paste")
			(net "I3C_SPD_DDREFGH_CPU1_LVC1_SDA")
		)
		(pad "6" smd rect
			(at -2.050034 -59.075066 270)
			(size 0.519938 1.4986)
			(layers "F.Cu" "F.Mask" "F.Paste")
			(net "GND")
		)
		(pad "7" smd rect
			(at -2.050034 -58.224928 270)
			(size 0.519938 1.4986)
			(layers "F.Cu" "F.Mask" "F.Paste")
			(net "M_H_CPU1_SA_DQ<0>")
		)
		(pad "8" smd rect
			(at -2.050034 -57.375044 270)
			(size 0.519938 1.4986)
			(layers "F.Cu" "F.Mask" "F.Paste")
			(net "GND")
		)
		(pad "9" smd rect
			(at -2.050034 -56.524906 270)
			(size 0.519938 1.4986)
			(layers "F.Cu" "F.Mask" "F.Paste")
			(net "M_H_CPU1_SA_DQ<1>")
		)
		(pad "10" smd rect
			(at -2.050034 -55.675022 270)
			(size 0.519938 1.4986)
			(layers "F.Cu" "F.Mask" "F.Paste")
			(net "GND")
		)
		(pad "11" smd rect
			(at -2.050034 -54.824884 270)
			(size 0.519938 1.4986)
			(layers "F.Cu" "F.Mask" "F.Paste")
			(net "M_H_CPU1_SA_DQS_DP<0>")
		)
		(pad "12" smd rect
			(at -2.050034 -53.975 270)
			(size 0.519938 1.4986)
			(layers "F.Cu" "F.Mask" "F.Paste")
			(net "M_H_CPU1_SA_DQS_DN<0>")
		)
		(pad "13" smd rect
			(at -2.050034 -53.125116 270)
			(size 0.519938 1.4986)
			(layers "F.Cu" "F.Mask" "F.Paste")
			(net "GND")
		)
		(pad "14" smd rect
			(at -2.050034 -52.274978 270)
			(size 0.519938 1.4986)
			(layers "F.Cu" "F.Mask" "F.Paste")
			(net "M_H_CPU1_SA_DQ<4>")
		)
		(pad "15" smd rect
			(at -2.050034 -51.425094 270)
			(size 0.519938 1.4986)
			(layers "F.Cu" "F.Mask" "F.Paste")
			(net "GND")
		)
		(pad "16" smd rect
			(at -2.050034 -50.574956 270)
			(size 0.519938 1.4986)
			(layers "F.Cu" "F.Mask" "F.Paste")
			(net "M_H_CPU1_SA_DQ<5>")
		)
		(pad "17" smd rect
			(at -2.050034 -49.725072 270)
			(size 0.519938 1.4986)
			(layers "F.Cu" "F.Mask" "F.Paste")
			(net "GND")
		)
		(pad "18" smd rect
			(at -2.050034 -48.874934 270)
			(size 0.519938 1.4986)
			(layers "F.Cu" "F.Mask" "F.Paste")
			(net "M_H_CPU1_SA_DQ<8>")
		)
		(pad "19" smd rect
			(at -2.050034 -48.02505 270)
			(size 0.519938 1.4986)
			(layers "F.Cu" "F.Mask" "F.Paste")
			(net "GND")
		)
		(pad "20" smd rect
			(at -2.050034 -47.174912 270)
			(size 0.519938 1.4986)
			(layers "F.Cu" "F.Mask" "F.Paste")
			(net "M_H_CPU1_SA_DQ<9>")
		)
		(pad "21" smd rect
			(at -2.050034 -46.325028 270)
			(size 0.519938 1.4986)
			(layers "F.Cu" "F.Mask" "F.Paste")
			(net "GND")
		)
		(pad "22" smd rect
			(at -2.050034 -45.47489 270)
			(size 0.519938 1.4986)
			(layers "F.Cu" "F.Mask" "F.Paste")
			(net "M_H_CPU1_SA_DQS_DP<1>")
		)
		(pad "23" smd rect
			(at -2.050034 -44.625006 270)
			(size 0.519938 1.4986)
			(layers "F.Cu" "F.Mask" "F.Paste")
			(net "M_H_CPU1_SA_DQS_DN<1>")
		)
		(pad "24" smd rect
			(at -2.050034 -43.775122 270)
			(size 0.519938 1.4986)
			(layers "F.Cu" "F.Mask" "F.Paste")
			(net "GND")
		)
		(pad "25" smd rect
			(at -2.050034 -42.924984 270)
			(size 0.519938 1.4986)
			(layers "F.Cu" "F.Mask" "F.Paste")
			(net "M_H_CPU1_SA_DQ<12>")
		)
		(pad "26" smd rect
			(at -2.050034 -42.0751 270)
			(size 0.519938 1.4986)
			(layers "F.Cu" "F.Mask" "F.Paste")
			(net "GND")
		)
		(pad "27" smd rect
			(at -2.050034 -41.224962 270)
			(size 0.519938 1.4986)
			(layers "F.Cu" "F.Mask" "F.Paste")
			(net "M_H_CPU1_SA_DQ<13>")
		)
		(pad "28" smd rect
			(at -2.050034 -40.375078 270)
			(size 0.519938 1.4986)
			(layers "F.Cu" "F.Mask" "F.Paste")
			(net "GND")
		)
		(pad "29" smd rect
			(at -2.050034 -39.52494 270)
			(size 0.519938 1.4986)
			(layers "F.Cu" "F.Mask" "F.Paste")
			(net "M_H_CPU1_SA_DQ<16>")
		)
		(pad "30" smd rect
			(at -2.050034 -38.675056 270)
			(size 0.519938 1.4986)
			(layers "F.Cu" "F.Mask" "F.Paste")
			(net "GND")
		)
		(pad "31" smd rect
			(at -2.050034 -37.824918 270)
			(size 0.519938 1.4986)
			(layers "F.Cu" "F.Mask" "F.Paste")
			(net "M_H_CPU1_SA_DQ<17>")
		)
		(pad "32" smd rect
			(at -2.050034 -36.975034 270)
			(size 0.519938 1.4986)
			(layers "F.Cu" "F.Mask" "F.Paste")
			(net "GND")
		)
		(pad "33" smd rect
			(at -2.050034 -36.124896 270)
			(size 0.519938 1.4986)
			(layers "F.Cu" "F.Mask" "F.Paste")
			(net "M_H_CPU1_SA_DQS_DP<2>")
		)
		(pad "34" smd rect
			(at -2.050034 -35.275012 270)
			(size 0.519938 1.4986)
			(layers "F.Cu" "F.Mask" "F.Paste")
			(net "M_H_CPU1_SA_DQS_DN<2>")
		)
		(pad "35" smd rect
			(at -2.050034 -34.425128 270)
			(size 0.519938 1.4986)
			(layers "F.Cu" "F.Mask" "F.Paste")
			(net "GND")
		)
		(pad "36" smd rect
			(at -2.050034 -33.57499 270)
			(size 0.519938 1.4986)
			(layers "F.Cu" "F.Mask" "F.Paste")
			(net "M_H_CPU1_SA_DQ<20>")
		)
		(pad "37" smd rect
			(at -2.050034 -32.725106 270)
			(size 0.519938 1.4986)
			(layers "F.Cu" "F.Mask" "F.Paste")
			(net "GND")
		)
		(pad "38" smd rect
			(at -2.050034 -31.874968 270)
			(size 0.519938 1.4986)
			(layers "F.Cu" "F.Mask" "F.Paste")
			(net "M_H_CPU1_SA_DQ<21>")
		)
		(pad "39" smd rect
			(at -2.050034 -31.025084 270)
			(size 0.519938 1.4986)
			(layers "F.Cu" "F.Mask" "F.Paste")
			(net "GND")
		)
		(pad "40" smd rect
			(at -2.050034 -30.174946 270)
			(size 0.519938 1.4986)
			(layers "F.Cu" "F.Mask" "F.Paste")
			(net "M_H_CPU1_SA_DQ<24>")
		)
		(pad "41" smd rect
			(at -2.050034 -29.325062 270)
			(size 0.519938 1.4986)
			(layers "F.Cu" "F.Mask" "F.Paste")
			(net "GND")
		)
		(pad "42" smd rect
			(at -2.050034 -28.474924 270)
			(size 0.519938 1.4986)
			(layers "F.Cu" "F.Mask" "F.Paste")
			(net "M_H_CPU1_SA_DQ<25>")
		)
		(pad "43" smd rect
			(at -2.050034 -27.62504 270)
			(size 0.519938 1.4986)
			(layers "F.Cu" "F.Mask" "F.Paste")
			(net "GND")
		)
		(pad "44" smd rect
			(at -2.050034 -26.774902 270)
			(size 0.519938 1.4986)
			(layers "F.Cu" "F.Mask" "F.Paste")
			(net "M_H_CPU1_SA_DQS_DP<3>")
		)
		(pad "45" smd rect
			(at -2.050034 -25.925018 270)
			(size 0.519938 1.4986)
			(layers "F.Cu" "F.Mask" "F.Paste")
			(net "M_H_CPU1_SA_DQS_DN<3>")
		)
		(pad "46" smd rect
			(at -2.050034 -25.07488 270)
			(size 0.519938 1.4986)
			(layers "F.Cu" "F.Mask" "F.Paste")
			(net "GND")
		)
		(pad "47" smd rect
			(at -2.050034 -24.224996 270)
			(size 0.519938 1.4986)
			(layers "F.Cu" "F.Mask" "F.Paste")
			(net "M_H_CPU1_SA_DQ<28>")
		)
		(pad "48" smd rect
			(at -2.050034 -23.375112 270)
			(size 0.519938 1.4986)
			(layers "F.Cu" "F.Mask" "F.Paste")
			(net "GND")
		)
		(pad "49" smd rect
			(at -2.050034 -22.524974 270)
			(size 0.519938 1.4986)
			(layers "F.Cu" "F.Mask" "F.Paste")
			(net "M_H_CPU1_SA_DQ<29>")
		)
		(pad "50" smd rect
			(at -2.050034 -21.67509 270)
			(size 0.519938 1.4986)
			(layers "F.Cu" "F.Mask" "F.Paste")
			(net "GND")
		)
		(pad "51" smd rect
			(at -2.050034 -20.824952 270)
			(size 0.519938 1.4986)
			(layers "F.Cu" "F.Mask" "F.Paste")
			(net "M_H_CPU1_SA_CB<0>")
		)
		(pad "52" smd rect
			(at -2.050034 -19.975068 270)
			(size 0.519938 1.4986)
			(layers "F.Cu" "F.Mask" "F.Paste")
			(net "GND")
		)
		(pad "53" smd rect
			(at -2.050034 -19.12493 270)
			(size 0.519938 1.4986)
			(layers "F.Cu" "F.Mask" "F.Paste")
			(net "M_H_CPU1_SA_CB<1>")
		)
		(pad "54" smd rect
			(at -2.050034 -18.275046 270)
			(size 0.519938 1.4986)
			(layers "F.Cu" "F.Mask" "F.Paste")
			(net "GND")
		)
		(pad "55" smd rect
			(at -2.050034 -17.424908 270)
			(size 0.519938 1.4986)
			(layers "F.Cu" "F.Mask" "F.Paste")
			(net "M_H_CPU1_SA_DQS_DP<4>")
		)
		(pad "56" smd rect
			(at -2.050034 -16.575024 270)
			(size 0.519938 1.4986)
			(layers "F.Cu" "F.Mask" "F.Paste")
			(net "M_H_CPU1_SA_DQS_DN<4>")
		)
		(pad "57" smd rect
			(at -2.050034 -15.724886 270)
			(size 0.519938 1.4986)
			(layers "F.Cu" "F.Mask" "F.Paste")
			(net "GND")
		)
		(pad "58" smd rect
			(at -2.050034 -14.875002 270)
			(size 0.519938 1.4986)
			(layers "F.Cu" "F.Mask" "F.Paste")
			(net "M_H_CPU1_SA_CB<4>")
		)
		(pad "59" smd rect
			(at -2.050034 -14.025118 270)
			(size 0.519938 1.4986)
			(layers "F.Cu" "F.Mask" "F.Paste")
			(net "GND")
		)
		(pad "60" smd rect
			(at -2.050034 -13.17498 270)
			(size 0.519938 1.4986)
			(layers "F.Cu" "F.Mask" "F.Paste")
			(net "M_H_CPU1_SA_CB<5>")
		)
		(pad "61" smd rect
			(at -2.050034 -12.325096 270)
			(size 0.519938 1.4986)
			(layers "F.Cu" "F.Mask" "F.Paste")
			(net "GND")
		)
		(pad "62" smd rect
			(at -2.050034 -11.474958 270)
			(size 0.519938 1.4986)
			(layers "F.Cu" "F.Mask" "F.Paste")
			(net "M_H_CPU1_ALERT_N")
		)
		(pad "63" smd rect
			(at -2.050034 -10.625074 270)
			(size 0.519938 1.4986)
			(layers "F.Cu" "F.Mask" "F.Paste")
			(net "GND")
		)
		(pad "64" smd rect
			(at -2.050034 -9.774936 270)
			(size 0.519938 1.4986)
			(layers "F.Cu" "F.Mask" "F.Paste")
			(net "M_H_CPU1_SA_CS_N<0>")
		)
		(pad "65" smd rect
			(at -2.050034 -8.925052 270)
			(size 0.519938 1.4986)
			(layers "F.Cu" "F.Mask" "F.Paste")
			(net "GND")
		)
		(pad "66" smd rect
			(at -2.050034 -8.074914 270)
			(size 0.519938 1.4986)
			(layers "F.Cu" "F.Mask" "F.Paste")
			(net "M_H_CPU1_SA_CA<0>")
		)
		(pad "67" smd rect
			(at -2.050034 -7.22503 270)
			(size 0.519938 1.4986)
			(layers "F.Cu" "F.Mask" "F.Paste")
			(net "GND")
		)
		(pad "68" smd rect
			(at -2.050034 -6.374892 270)
			(size 0.519938 1.4986)
			(layers "F.Cu" "F.Mask" "F.Paste")
			(net "M_H_CPU1_SA_CA<2>")
		)
		(pad "69" smd rect
			(at -2.050034 -5.525008 270)
			(size 0.519938 1.4986)
			(layers "F.Cu" "F.Mask" "F.Paste")
			(net "GND")
		)
		(pad "70" smd rect
			(at -2.050034 -4.675124 270)
			(size 0.519938 1.4986)
			(layers "F.Cu" "F.Mask" "F.Paste")
			(net "M_H_CPU1_SA_CA<4>")
		)
		(pad "71" smd rect
			(at -2.050034 -3.824986 270)
			(size 0.519938 1.4986)
			(layers "F.Cu" "F.Mask" "F.Paste")
			(net "GND")
		)
		(pad "72" smd rect
			(at -2.050034 -2.975102 270)
			(size 0.519938 1.4986)
			(layers "F.Cu" "F.Mask" "F.Paste")
			(net "M_H_CPU1_SA_CA<6>")
		)
		(pad "73" smd rect
			(at -2.050034 -2.124964 270)
			(size 0.519938 1.4986)
			(layers "F.Cu" "F.Mask" "F.Paste")
			(net "GND")
		)
		(pad "74" smd rect
			(at -2.050034 -1.27508 270)
			(size 0.519938 1.4986)
			(layers "F.Cu" "F.Mask" "F.Paste")
			(net "M_H_CPU1_SA_PAR")
		)
		(pad "75" smd rect
			(at -2.050034 -0.424942 270)
			(size 0.519938 1.4986)
			(layers "F.Cu" "F.Mask" "F.Paste")
			(net "GND")
		)
		(pad "76" smd rect
			(at -2.050034 5.525008 270)
			(size 0.519938 1.4986)
			(layers "F.Cu" "F.Mask" "F.Paste")
			(net "M_H_CPU1_SB_CA<0>")
		)
		(pad "77" smd rect
			(at -2.050034 6.374892 270)
			(size 0.519938 1.4986)
			(layers "F.Cu" "F.Mask" "F.Paste")
			(net "GND")
		)
		(pad "78" smd rect
			(at -2.050034 7.22503 270)
			(size 0.519938 1.4986)
			(layers "F.Cu" "F.Mask" "F.Paste")
			(net "M_H_CPU1_SB_CA<2>")
		)
		(pad "79" smd rect
			(at -2.050034 8.074914 270)
			(size 0.519938 1.4986)
			(layers "F.Cu" "F.Mask" "F.Paste")
			(net "GND")
		)
		(pad "80" smd rect
			(at -2.050034 8.925052 270)
			(size 0.519938 1.4986)
			(layers "F.Cu" "F.Mask" "F.Paste")
			(net "M_H_CPU1_SB_CA<4>")
		)
		(pad "81" smd rect
			(at -2.050034 9.774936 270)
			(size 0.519938 1.4986)
			(layers "F.Cu" "F.Mask" "F.Paste")
			(net "GND")
		)
		(pad "82" smd rect
			(at -2.050034 10.625074 270)
			(size 0.519938 1.4986)
			(layers "F.Cu" "F.Mask" "F.Paste")
			(net "M_H_CPU1_SB_CA<6>")
		)
		(pad "83" smd rect
			(at -2.050034 11.474958 270)
			(size 0.519938 1.4986)
			(layers "F.Cu" "F.Mask" "F.Paste")
			(net "GND")
		)
		(pad "84" smd rect
			(at -2.050034 12.325096 270)
			(size 0.519938 1.4986)
			(layers "F.Cu" "F.Mask" "F.Paste")
			(net "M_H_CPU1_SB_CS_N<0>")
		)
		(pad "85" smd rect
			(at -2.050034 13.17498 270)
			(size 0.519938 1.4986)
			(layers "F.Cu" "F.Mask" "F.Paste")
			(net "GND")
		)
		(pad "86" smd rect
			(at -2.050034 14.025118 270)
			(size 0.519938 1.4986)
			(layers "F.Cu" "F.Mask" "F.Paste")
			(net "M_H_CPU1_SA_RSP<0>")
		)
		(pad "87" smd rect
			(at -2.050034 14.875002 270)
			(size 0.519938 1.4986)
			(layers "F.Cu" "F.Mask" "F.Paste")
			(net "M_H_CPU1_SB_RSP<0>")
		)
		(pad "88" smd rect
			(at -2.050034 15.724886 270)
			(size 0.519938 1.4986)
			(layers "F.Cu" "F.Mask" "F.Paste")
			(net "GND")
		)
		(pad "89" smd rect
			(at -2.050034 16.575024 270)
			(size 0.519938 1.4986)
			(layers "F.Cu" "F.Mask" "F.Paste")
			(net "M_H_CPU1_SB_CB<4>")
		)
		(pad "90" smd rect
			(at -2.050034 17.424908 270)
			(size 0.519938 1.4986)
			(layers "F.Cu" "F.Mask" "F.Paste")
			(net "GND")
		)
		(pad "91" smd rect
			(at -2.050034 18.275046 270)
			(size 0.519938 1.4986)
			(layers "F.Cu" "F.Mask" "F.Paste")
			(net "M_H_CPU1_SB_CB<5>")
		)
		(pad "92" smd rect
			(at -2.050034 19.12493 270)
			(size 0.519938 1.4986)
			(layers "F.Cu" "F.Mask" "F.Paste")
			(net "GND")
		)
		(pad "93" smd rect
			(at -2.050034 19.975068 270)
			(size 0.519938 1.4986)
			(layers "F.Cu" "F.Mask" "F.Paste")
			(net "M_H_CPU1_SB_DQS_DP<9>")
		)
		(pad "94" smd rect
			(at -2.050034 20.824952 270)
			(size 0.519938 1.4986)
			(layers "F.Cu" "F.Mask" "F.Paste")
			(net "M_H_CPU1_SB_DQS_DN<9>")
		)
		(pad "95" smd rect
			(at -2.050034 21.67509 270)
			(size 0.519938 1.4986)
			(layers "F.Cu" "F.Mask" "F.Paste")
			(net "GND")
		)
		(pad "96" smd rect
			(at -2.050034 22.524974 270)
			(size 0.519938 1.4986)
			(layers "F.Cu" "F.Mask" "F.Paste")
			(net "M_H_CPU1_SB_CB<0>")
		)
		(pad "97" smd rect
			(at -2.050034 23.375112 270)
			(size 0.519938 1.4986)
			(layers "F.Cu" "F.Mask" "F.Paste")
			(net "GND")
		)
		(pad "98" smd rect
			(at -2.050034 24.224996 270)
			(size 0.519938 1.4986)
			(layers "F.Cu" "F.Mask" "F.Paste")
			(net "M_H_CPU1_SB_CB<1>")
		)
		(pad "99" smd rect
			(at -2.050034 25.07488 270)
			(size 0.519938 1.4986)
			(layers "F.Cu" "F.Mask" "F.Paste")
			(net "GND")
		)
		(pad "100" smd rect
			(at -2.050034 25.925018 270)
			(size 0.519938 1.4986)
			(layers "F.Cu" "F.Mask" "F.Paste")
			(net "M_H_CPU1_SB_DQ<0>")
		)
		(pad "101" smd rect
			(at -2.050034 26.774902 270)
			(size 0.519938 1.4986)
			(layers "F.Cu" "F.Mask" "F.Paste")
			(net "GND")
		)
		(pad "102" smd rect
			(at -2.050034 27.62504 270)
			(size 0.519938 1.4986)
			(layers "F.Cu" "F.Mask" "F.Paste")
			(net "M_H_CPU1_SB_DQ<1>")
		)
		(pad "103" smd rect
			(at -2.050034 28.474924 270)
			(size 0.519938 1.4986)
			(layers "F.Cu" "F.Mask" "F.Paste")
			(net "GND")
		)
		(pad "104" smd rect
			(at -2.050034 29.325062 270)
			(size 0.519938 1.4986)
			(layers "F.Cu" "F.Mask" "F.Paste")
			(net "M_H_CPU1_SB_DQS_DP<0>")
		)
		(pad "105" smd rect
			(at -2.050034 30.174946 270)
			(size 0.519938 1.4986)
			(layers "F.Cu" "F.Mask" "F.Paste")
			(net "M_H_CPU1_SB_DQS_DN<0>")
		)
		(pad "106" smd rect
			(at -2.050034 31.025084 270)
			(size 0.519938 1.4986)
			(layers "F.Cu" "F.Mask" "F.Paste")
			(net "GND")
		)
		(pad "107" smd rect
			(at -2.050034 31.874968 270)
			(size 0.519938 1.4986)
			(layers "F.Cu" "F.Mask" "F.Paste")
			(net "M_H_CPU1_SB_DQ<4>")
		)
		(pad "108" smd rect
			(at -2.050034 32.725106 270)
			(size 0.519938 1.4986)
			(layers "F.Cu" "F.Mask" "F.Paste")
			(net "GND")
		)
		(pad "109" smd rect
			(at -2.050034 33.57499 270)
			(size 0.519938 1.4986)
			(layers "F.Cu" "F.Mask" "F.Paste")
			(net "M_H_CPU1_SB_DQ<5>")
		)
		(pad "110" smd rect
			(at -2.050034 34.425128 270)
			(size 0.519938 1.4986)
			(layers "F.Cu" "F.Mask" "F.Paste")
			(net "GND")
		)
		(pad "111" smd rect
			(at -2.050034 35.275012 270)
			(size 0.519938 1.4986)
			(layers "F.Cu" "F.Mask" "F.Paste")
			(net "M_H_CPU1_SB_DQ<8>")
		)
		(pad "112" smd rect
			(at -2.050034 36.124896 270)
			(size 0.519938 1.4986)
			(layers "F.Cu" "F.Mask" "F.Paste")
			(net "GND")
		)
	)
)
